(kicad_pcb
	(version 20260206)
	(generator "pcbnew")
	(generator_version "10.0")
	(general
		(thickness 1.6)
		(legacy_teardrops no)
	)
	(paper "A4")
	(title_block
		(title "04192023_DAF0TMB3IC0_F0TG_MB_C_brd_V02_OCP.brd")
		(comment 1 "Grand Teton / footprints 1001-1005 of 8354")
	)
	(layers
		(0 "F.Cu" signal "TOP")
		(4 "In1.Cu" signal "GND")
		(6 "In2.Cu" signal "IN1")
		(8 "In3.Cu" signal "GND1")
		(10 "In4.Cu" signal "IN2")
		(12 "In5.Cu" signal "GND2")
		(14 "In6.Cu" signal "IN3")
		(16 "In7.Cu" signal "GND3")
		(18 "In8.Cu" signal "VCC")
		(20 "In9.Cu" signal "VCC1")
		(22 "In10.Cu" signal "GND4")
		(24 "In11.Cu" signal "IN4")
		(26 "In12.Cu" signal "GND5")
		(28 "In13.Cu" signal "IN5")
		(30 "In14.Cu" signal "GND6")
		(32 "In15.Cu" signal "IN6")
		(34 "In16.Cu" signal "GND7")
		(2 "B.Cu" signal "BOTTOM")
		(9 "F.Adhes" user "F.Adhesive")
		(11 "B.Adhes" user "B.Adhesive")
		(13 "F.Paste" user "Package Geometry/Pastemask Top")
		(15 "B.Paste" user "Package Geometry/Pastemask Bottom")
		(5 "F.SilkS" user "Ref Des/Silkscreen Top")
		(7 "B.SilkS" user "Ref Des/Silkscreen Bottom")
		(1 "F.Mask" user "Board Geometry/Soldermask Top")
		(3 "B.Mask" user "Board Geometry/Soldermask Bottom")
		(17 "Dwgs.User" user "User.Drawings")
		(19 "Cmts.User" user "User.Comments")
		(21 "Eco1.User" user "User.Eco1")
		(23 "Eco2.User" user "User.Eco2")
		(25 "Edge.Cuts" user "Board Geometry/Outline")
		(27 "Margin" user)
		(31 "F.CrtYd" user "Package Geometry/Place Bound Top")
		(29 "B.CrtYd" user "Package Geometry/Place Bound Bottom")
		(35 "F.Fab" user "Ref Des/Assembly Top")
		(33 "B.Fab" user "Ref Des/Assembly Bottom")
	)
	(footprint ""
		(layer "F.Cu")
		(at 189.738762 -25.643332)
		(property "Reference" "PU300"
			(at 3.987546 -1.268222 0)
			(unlocked yes)
			(layer "F.SilkS")
			(effects
				(font
					(size 0.7874 0.5842)
					(thickness 0.1524)
				)
				(justify left)
			)
		)
		(property "Value" ""
			(at 0 0 0)
			(layer "F.Fab")
			(effects
				(font
					(size 1.27 1.27)
				)
			)
		)
		(duplicate_pad_numbers_are_jumpers no)
		(fp_line
			(start -1.774952 -1.039876)
			(end -1.774952 1.039876)
			(stroke
				(width 0.1524)
				(type default)
			)
			(layer "F.SilkS")
		)
		(fp_line
			(start -1.774952 1.039876)
			(end 1.774952 1.039876)
			(stroke
				(width 0.1524)
				(type default)
			)
			(layer "F.SilkS")
		)
		(fp_line
			(start 1.774952 -1.039876)
			(end -1.774952 -1.039876)
			(stroke
				(width 0.1524)
				(type default)
			)
			(layer "F.SilkS")
		)
		(fp_line
			(start 1.774952 1.039876)
			(end 1.774952 -1.039876)
			(stroke
				(width 0.1524)
				(type default)
			)
			(layer "F.SilkS")
		)
		(fp_poly
			(pts
				(xy -0.999998 -1.801876) (xy -0.999998 -1.039876) (xy -1.769872 -1.039876) (xy -1.769872 -0.249936)
				(xy -2.531872 -0.249936) (xy -2.531872 -1.801876)
			)
			(stroke
				(width 0)
				(type default)
			)
			(fill yes)
			(layer "F.SilkS")
		)
		(fp_line
			(start -1.769872 -1.039876)
			(end -1.769872 1.039876)
			(stroke
				(width 0.1)
				(type default)
			)
			(layer "F.Fab")
		)
		(fp_line
			(start -1.769872 1.039876)
			(end 1.769872 1.039876)
			(stroke
				(width 0.1)
				(type default)
			)
			(layer "F.Fab")
		)
		(fp_line
			(start 1.769872 -1.039876)
			(end -1.769872 -1.039876)
			(stroke
				(width 0.1)
				(type default)
			)
			(layer "F.Fab")
		)
		(fp_line
			(start 1.769872 1.039876)
			(end 1.769872 -1.039876)
			(stroke
				(width 0.1)
				(type default)
			)
			(layer "F.Fab")
		)
		(fp_poly
			(pts
				(xy -1.769872 -1.039876) (xy -0.999998 -1.039876) (xy -0.999998 -1.801876) (xy -2.531872 -1.801876)
				(xy -2.531872 -0.249936) (xy -1.769872 -0.249936)
			)
			(stroke
				(width 0)
				(type default)
			)
			(fill yes)
			(layer "F.Fab")
		)
		(pad "A1" smd circle
			(at -1.500124 -0.750062)
			(size 0.2286 0.2286)
			(layers "F.Cu" "F.Mask" "F.Paste")
			(net "P12V_SCM_SENSE")
		)
		(pad "A2" smd circle
			(at -0.999998 -0.750062)
			(size 0.2286 0.2286)
			(layers "F.Cu" "F.Mask" "F.Paste")
			(net "P12V_SCM_VCC")
		)
		(pad "A3" smd circle
			(at -0.499872 -0.750062)
			(size 0.2286 0.2286)
			(layers "F.Cu" "F.Mask" "F.Paste")
			(net "P12V_AUX")
		)
		(pad "A4" smd circle
			(at 0 -0.750062)
			(size 0.2286 0.2286)
			(layers "F.Cu" "F.Mask" "F.Paste")
			(net "P12V_SCM_R")
		)
		(pad "A5" smd circle
			(at 0.499872 -0.750062)
			(size 0.2286 0.2286)
			(layers "F.Cu" "F.Mask" "F.Paste")
			(net "P12V_AUX")
		)
		(pad "A6" smd circle
			(at 0.999998 -0.750062)
			(size 0.2286 0.2286)
			(layers "F.Cu" "F.Mask" "F.Paste")
			(net "P12V_SCM_GATE")
		)
		(pad "A7" smd circle
			(at 1.500124 -0.750062)
			(size 0.2286 0.2286)
			(layers "F.Cu" "F.Mask" "F.Paste")
			(net "GND")
		)
		(pad "B1" smd circle
			(at -1.500124 -0.249936)
			(size 0.2286 0.2286)
			(layers "F.Cu" "F.Mask" "F.Paste")
			(net "P12V_SCM_CB")
		)
		(pad "B2" smd circle
			(at -0.999998 -0.249936)
			(size 0.2286 0.2286)
			(layers "F.Cu" "F.Mask" "F.Paste")
			(net "GND")
		)
		(pad "B3" smd circle
			(at -0.499872 -0.249936)
			(size 0.2286 0.2286)
			(layers "F.Cu" "F.Mask" "F.Paste")
			(net "P12V_AUX")
		)
		(pad "B4" smd circle
			(at 0 -0.249936)
			(size 0.2286 0.2286)
			(layers "F.Cu" "F.Mask" "F.Paste")
			(net "P12V_SCM_R")
		)
		(pad "B5" smd circle
			(at 0.499872 -0.249936)
			(size 0.2286 0.2286)
			(layers "F.Cu" "F.Mask" "F.Paste")
			(net "P12V_AUX")
		)
		(pad "B6" smd circle
			(at 0.999998 -0.249936)
			(size 0.2286 0.2286)
			(layers "F.Cu" "F.Mask" "F.Paste")
			(net "P12V_SCM_R")
		)
		(pad "B7" smd circle
			(at 1.500124 -0.249936)
			(size 0.2286 0.2286)
			(layers "F.Cu" "F.Mask" "F.Paste")
			(net "GND")
		)
		(pad "C1" smd circle
			(at -1.500124 0.249936)
			(size 0.2286 0.2286)
			(layers "F.Cu" "F.Mask" "F.Paste")
			(net "GND")
		)
		(pad "C2" smd circle
			(at -0.999998 0.249936)
			(size 0.2286 0.2286)
			(layers "F.Cu" "F.Mask" "F.Paste")
			(net "GND")
		)
		(pad "C3" smd circle
			(at -0.499872 0.249936)
			(size 0.2286 0.2286)
			(layers "F.Cu" "F.Mask" "F.Paste")
			(net "P12V_AUX")
		)
		(pad "C4" smd circle
			(at 0 0.249936)
			(size 0.2286 0.2286)
			(layers "F.Cu" "F.Mask" "F.Paste")
			(net "P12V_SCM_R")
		)
		(pad "C5" smd circle
			(at 0.499872 0.249936)
			(size 0.2286 0.2286)
			(layers "F.Cu" "F.Mask" "F.Paste")
			(net "P12V_AUX")
		)
		(pad "C6" smd circle
			(at 0.999998 0.249936)
			(size 0.2286 0.2286)
			(layers "F.Cu" "F.Mask" "F.Paste")
			(net "P12V_SCM_R")
		)
		(pad "C7" smd circle
			(at 1.500124 0.249936)
			(size 0.2286 0.2286)
			(layers "F.Cu" "F.Mask" "F.Paste")
			(net "P12V_SCM_FAULT_N")
		)
		(pad "D1" smd circle
			(at -1.500124 0.750062)
			(size 0.2286 0.2286)
			(layers "F.Cu" "F.Mask" "F.Paste")
			(net "P12V_SCM_REG")
		)
		(pad "D2" smd circle
			(at -0.999998 0.750062)
			(size 0.2286 0.2286)
			(layers "F.Cu" "F.Mask" "F.Paste")
			(net "P12V_SCM_UV")
		)
		(pad "D3" smd circle
			(at -0.499872 0.750062)
			(size 0.2286 0.2286)
			(layers "F.Cu" "F.Mask" "F.Paste")
			(net "P12V_SCM_OV")
		)
		(pad "D4" smd circle
			(at 0 0.750062)
			(size 0.2286 0.2286)
			(layers "F.Cu" "F.Mask" "F.Paste")
			(net "P12V_SCM_R")
		)
		(pad "D5" smd circle
			(at 0.499872 0.750062)
			(size 0.2286 0.2286)
			(layers "F.Cu" "F.Mask" "F.Paste")
			(net "P12V_AUX")
		)
		(pad "D6" smd circle
			(at 0.999998 0.750062)
			(size 0.2286 0.2286)
			(layers "F.Cu" "F.Mask" "F.Paste")
			(net "P12V_SCM_R")
		)
		(pad "D7" smd circle
			(at 1.500124 0.750062)
			(size 0.2286 0.2286)
			(layers "F.Cu" "F.Mask" "F.Paste")
			(net "P12V_SCM_PWRGD")
		)
	)
	(footprint ""
		(layer "F.Cu")
		(at 395.374622 -416.899344 -90)
		(property "Reference" "C6582"
			(at 0 0 270)
			(layer "F.SilkS")
			(hide yes)
			(effects
				(font
					(size 1.27 1.27)
				)
			)
		)
		(property "Value" ""
			(at 0 0 270)
			(layer "F.Fab")
			(effects
				(font
					(size 1.27 1.27)
				)
			)
		)
		(duplicate_pad_numbers_are_jumpers no)
		(fp_line
			(start -0.299974 0.150114)
			(end -0.299974 -0.150114)
			(stroke
				(width 0.1)
				(type default)
			)
			(layer "F.Fab")
		)
		(fp_line
			(start 0.299974 0.150114)
			(end -0.299974 0.150114)
			(stroke
				(width 0.1)
				(type default)
			)
			(layer "F.Fab")
		)
		(fp_line
			(start -0.299974 -0.150114)
			(end 0.299974 -0.150114)
			(stroke
				(width 0.1)
				(type default)
			)
			(layer "F.Fab")
		)
		(fp_line
			(start 0.299974 -0.150114)
			(end 0.299974 0.150114)
			(stroke
				(width 0.1)
				(type default)
			)
			(layer "F.Fab")
		)
		(pad "1" smd rect
			(at -0.2667 0 270)
			(size 0.3048 0.381)
			(layers "F.Cu" "F.Mask" "F.Paste")
			(net "P5E_CPU0_P2_TX_BUF_C_DN<8>")
		)
		(pad "2" smd rect
			(at 0.2667 0 270)
			(size 0.3048 0.381)
			(layers "F.Cu" "F.Mask" "F.Paste")
			(net "P5E_CPU0_P2_TX_BUF_DN<8>")
		)
	)
	(footprint ""
		(layer "F.Cu")
		(at 414.316418 -365.764064)
		(property "Reference" "R117"
			(at 0 0 0)
			(layer "F.SilkS")
			(hide yes)
			(effects
				(font
					(size 1.27 1.27)
				)
			)
		)
		(property "Value" ""
			(at 0 0 0)
			(layer "F.Fab")
			(effects
				(font
					(size 1.27 1.27)
				)
			)
		)
		(duplicate_pad_numbers_are_jumpers no)
		(fp_line
			(start -0.7874 -0.4064)
			(end 0.7874 -0.4064)
			(stroke
				(width 0.1524)
				(type default)
			)
			(layer "F.SilkS")
		)
		(fp_line
			(start -0.7874 0.4064)
			(end -0.7874 -0.4064)
			(stroke
				(width 0.1524)
				(type default)
			)
			(layer "F.SilkS")
		)
		(fp_line
			(start 0.7874 -0.4064)
			(end 0.7874 0.4064)
			(stroke
				(width 0.1524)
				(type default)
			)
			(layer "F.SilkS")
		)
		(fp_line
			(start 0.7874 0.4064)
			(end -0.7874 0.4064)
			(stroke
				(width 0.1524)
				(type default)
			)
			(layer "F.SilkS")
		)
		(fp_line
			(start -0.67945 -0.305054)
			(end -0.12065 -0.305054)
			(stroke
				(width 0.1)
				(type default)
			)
			(layer "F.Fab")
		)
		(fp_line
			(start -0.67945 0.3048)
			(end -0.67945 -0.305054)
			(stroke
				(width 0.1)
				(type default)
			)
			(layer "F.Fab")
		)
		(fp_line
			(start -0.12065 -0.305054)
			(end -0.12065 -0.2794)
			(stroke
				(width 0.1)
				(type default)
			)
			(layer "F.Fab")
		)
		(fp_line
			(start -0.12065 -0.2794)
			(end 0.12065 -0.2794)
			(stroke
				(width 0.1)
				(type default)
			)
			(layer "F.Fab")
		)
		(fp_line
			(start -0.12065 0.2794)
			(end -0.12065 0.3048)
			(stroke
				(width 0.1)
				(type default)
			)
			(layer "F.Fab")
		)
		(fp_line
			(start -0.12065 0.3048)
			(end -0.67945 0.3048)
			(stroke
				(width 0.1)
				(type default)
			)
			(layer "F.Fab")
		)
		(fp_line
			(start 0.120396 0.2794)
			(end -0.12065 0.2794)
			(stroke
				(width 0.1)
				(type default)
			)
			(layer "F.Fab")
		)
		(fp_line
			(start 0.120396 0.3048)
			(end 0.120396 0.2794)
			(stroke
				(width 0.1)
				(type default)
			)
			(layer "F.Fab")
		)
		(fp_line
			(start 0.12065 -0.3048)
			(end 0.67945 -0.3048)
			(stroke
				(width 0.1)
				(type default)
			)
			(layer "F.Fab")
		)
		(fp_line
			(start 0.12065 -0.2794)
			(end 0.12065 -0.3048)
			(stroke
				(width 0.1)
				(type default)
			)
			(layer "F.Fab")
		)
		(fp_line
			(start 0.67945 -0.3048)
			(end 0.67945 0.3048)
			(stroke
				(width 0.1)
				(type default)
			)
			(layer "F.Fab")
		)
		(fp_line
			(start 0.67945 0.3048)
			(end 0.120396 0.3048)
			(stroke
				(width 0.1)
				(type default)
			)
			(layer "F.Fab")
		)
		(pad "1" smd circle
			(at -0.40005 0)
			(size 0 0)
			(layers "F.Cu" "F.Mask" "F.Paste")
			(net "P3V3_AUX")
		)
		(pad "2" smd circle
			(at 0.40005 0)
			(size 0 0)
			(layers "F.Cu" "F.Mask" "F.Paste")
			(net "PWRGD_PVDD11_S3_P0_R")
		)
	)
	(footprint ""
		(layer "F.Cu")
		(at 419.966902 -349.380556 90)
		(property "Reference" "PR482"
			(at 0 0 90)
			(layer "F.SilkS")
			(hide yes)
			(effects
				(font
					(size 1.27 1.27)
				)
			)
		)
		(property "Value" ""
			(at 0 0 90)
			(layer "F.Fab")
			(effects
				(font
					(size 1.27 1.27)
				)
			)
		)
		(duplicate_pad_numbers_are_jumpers no)
		(fp_line
			(start 0.7874 -0.4064)
			(end 0.7874 0.4064)
			(stroke
				(width 0.1524)
				(type default)
			)
			(layer "F.SilkS")
		)
		(fp_line
			(start -0.7874 -0.4064)
			(end 0.7874 -0.4064)
			(stroke
				(width 0.1524)
				(type default)
			)
			(layer "F.SilkS")
		)
		(fp_line
			(start 0.7874 0.4064)
			(end -0.7874 0.4064)
			(stroke
				(width 0.1524)
				(type default)
			)
			(layer "F.SilkS")
		)
		(fp_line
			(start -0.7874 0.4064)
			(end -0.7874 -0.4064)
			(stroke
				(width 0.1524)
				(type default)
			)
			(layer "F.SilkS")
		)
		(fp_line
			(start -0.12065 -0.305054)
			(end -0.12065 -0.2794)
			(stroke
				(width 0.1)
				(type default)
			)
			(layer "F.Fab")
		)
		(fp_line
			(start -0.67945 -0.305054)
			(end -0.12065 -0.305054)
			(stroke
				(width 0.1)
				(type default)
			)
			(layer "F.Fab")
		)
		(fp_line
			(start 0.67945 -0.3048)
			(end 0.67945 0.3048)
			(stroke
				(width 0.1)
				(type default)
			)
			(layer "F.Fab")
		)
		(fp_line
			(start 0.12065 -0.3048)
			(end 0.67945 -0.3048)
			(stroke
				(width 0.1)
				(type default)
			)
			(layer "F.Fab")
		)
		(fp_line
			(start 0.12065 -0.2794)
			(end 0.12065 -0.3048)
			(stroke
				(width 0.1)
				(type default)
			)
			(layer "F.Fab")
		)
		(fp_line
			(start -0.12065 -0.2794)
			(end 0.12065 -0.2794)
			(stroke
				(width 0.1)
				(type default)
			)
			(layer "F.Fab")
		)
		(fp_line
			(start 0.120396 0.2794)
			(end -0.12065 0.2794)
			(stroke
				(width 0.1)
				(type default)
			)
			(layer "F.Fab")
		)
		(fp_line
			(start -0.12065 0.2794)
			(end -0.12065 0.3048)
			(stroke
				(width 0.1)
				(type default)
			)
			(layer "F.Fab")
		)
		(fp_line
			(start 0.67945 0.3048)
			(end 0.120396 0.3048)
			(stroke
				(width 0.1)
				(type default)
			)
			(layer "F.Fab")
		)
		(fp_line
			(start 0.120396 0.3048)
			(end 0.120396 0.2794)
			(stroke
				(width 0.1)
				(type default)
			)
			(layer "F.Fab")
		)
		(fp_line
			(start -0.12065 0.3048)
			(end -0.67945 0.3048)
			(stroke
				(width 0.1)
				(type default)
			)
			(layer "F.Fab")
		)
		(fp_line
			(start -0.67945 0.3048)
			(end -0.67945 -0.305054)
			(stroke
				(width 0.1)
				(type default)
			)
			(layer "F.Fab")
		)
		(pad "1" smd circle
			(at -0.40005 0 90)
			(size 0 0)
			(layers "F.Cu" "F.Mask" "F.Paste")
			(net "SW_PVDD11_S3_P0_SW1_RC")
		)
		(pad "2" smd circle
			(at 0.40005 0 90)
			(size 0 0)
			(layers "F.Cu" "F.Mask" "F.Paste")
			(net "GND")
		)
	)
	(footprint ""
		(layer "F.Cu")
		(at 254.362966 -68.946522)
		(property "Reference" "Q126"
			(at -1.4224 -1.768348 0)
			(unlocked yes)
			(layer "F.SilkS")
			(effects
				(font
					(size 0.7874 0.5842)
					(thickness 0.1524)
				)
				(justify left)
			)
		)
		(property "Value" ""
			(at 0 0 0)
			(layer "F.Fab")
			(effects
				(font
					(size 1.27 1.27)
				)
			)
		)
		(duplicate_pad_numbers_are_jumpers no)
		(fp_line
			(start -1.332738 -1.100074)
			(end -0.4826 -1.100074)
			(stroke
				(width 0.1524)
				(type default)
			)
			(layer "F.SilkS")
		)
		(fp_line
			(start -1.332738 1.100074)
			(end -1.332738 -1.100074)
			(stroke
				(width 0.1524)
				(type default)
			)
			(layer "F.SilkS")
		)
		(fp_line
			(start -0.4826 -1.100074)
			(end 0 -0.541274)
			(stroke
				(width 0.1524)
				(type default)
			)
			(layer "F.SilkS")
		)
		(fp_line
			(start 0 -0.541274)
			(end 0.4826 -1.100074)
			(stroke
				(width 0.1524)
				(type default)
			)
			(layer "F.SilkS")
		)
		(fp_line
			(start 0.4826 -1.100074)
			(end 1.332738 -1.100074)
			(stroke
				(width 0.1524)
				(type default)
			)
			(layer "F.SilkS")
		)
		(fp_line
			(start 1.332738 -1.100074)
			(end 1.332738 1.100074)
			(stroke
				(width 0.1524)
				(type default)
			)
			(layer "F.SilkS")
		)
		(fp_line
			(start 1.332738 1.100074)
			(end -1.332738 1.100074)
			(stroke
				(width 0.1524)
				(type default)
			)
			(layer "F.SilkS")
		)
		(fp_poly
			(pts
				(xy -1.909064 -0.710184) (xy -2.61112 -0.359156) (xy -2.61112 -1.061212)
			)
			(stroke
				(width 0)
				(type default)
			)
			(fill yes)
			(layer "F.SilkS")
		)
		(fp_line
			(start -0.674878 -1.100074)
			(end 0.674878 -1.100074)
			(stroke
				(width 0.1)
				(type default)
			)
			(layer "F.Fab")
		)
		(fp_line
			(start -0.674878 1.100074)
			(end -0.674878 -1.100074)
			(stroke
				(width 0.1)
				(type default)
			)
			(layer "F.Fab")
		)
		(fp_line
			(start 0.674878 -1.100074)
			(end 0.674878 1.100074)
			(stroke
				(width 0.1)
				(type default)
			)
			(layer "F.Fab")
		)
		(fp_line
			(start 0.674878 1.100074)
			(end -0.674878 1.100074)
			(stroke
				(width 0.1)
				(type default)
			)
			(layer "F.Fab")
		)
		(fp_poly
			(pts
				(xy -2.2352 -0.298958) (xy -2.2352 -1.001014) (xy -1.533144 -0.649986)
			)
			(stroke
				(width 0)
				(type default)
			)
			(fill yes)
			(layer "F.Fab")
		)
		(pad "1" smd rect
			(at -0.94996 -0.649986 90)
			(size 0.4318 0.508)
			(layers "F.Cu" "F.Mask" "F.Paste")
			(net "GND")
		)
		(pad "2" smd rect
			(at -0.94996 0 90)
			(size 0.4318 0.508)
			(layers "F.Cu" "F.Mask" "F.Paste")
			(net "P3V3_E1S_EN_0_R")
		)
		(pad "3" smd rect
			(at -0.94996 0.649986 90)
			(size 0.4318 0.508)
			(layers "F.Cu" "F.Mask" "F.Paste")
			(net "P3V3_E1S_UV_0_R")
		)
		(pad "4" smd rect
			(at 0.94996 0.649986 90)
			(size 0.4318 0.508)
			(layers "F.Cu" "F.Mask" "F.Paste")
			(net "GND")
		)
		(pad "5" smd rect
			(at 0.94996 0 90)
			(size 0.4318 0.508)
			(layers "F.Cu" "F.Mask" "F.Paste")
			(net "P3V3_E1S_0_EN_G")
		)
		(pad "6" smd rect
			(at 0.94996 -0.649986 90)
			(size 0.4318 0.508)
			(layers "F.Cu" "F.Mask" "F.Paste")
			(net "P3V3_E1S_0_EN_G")
		)
	)
)
